# T6G (Grand Teton) — schematic netlist excerpt (pin names and nets, part order shuffled) for the footprints in the layout excerpt that follows; sources: Cadence DE-HDL packaged netlist, KiCad conversion of 04192023_DAF0TMB3IC0_F0TG_MB_C_brd_V02_OCP.brd

PR6621  Q_RES  2.2 5% CHIP  pkg 0402LF  page 365 : A = P0V9_RETIMER_CPU1_PVCC ; B = P0V9_RETIMER_CPU1_VCC1
R3777  Q_RES  0 5% CHIP  pkg 0402LF  page 150 : A = FM_UARTSW_LSB_N ; B = FM_UARTSW_LSB_R

(kicad_pcb
	(version 20260206)
	(generator "pcbnew")
	(generator_version "10.0")
	(general
		(thickness 1.6)
		(legacy_teardrops no)
	)
	(paper "A4")
	(title_block
		(title "04192023_DAF0TMB3IC0_F0TG_MB_C_brd_V02_OCP.brd")
		(comment 1 "Grand Teton / footprints 8117-8118 of 8354")
	)
	(layers
		(0 "F.Cu" signal "TOP")
		(4 "In1.Cu" signal "GND")
		(6 "In2.Cu" signal "IN1")
		(8 "In3.Cu" signal "GND1")
		(10 "In4.Cu" signal "IN2")
		(12 "In5.Cu" signal "GND2")
		(14 "In6.Cu" signal "IN3")
		(16 "In7.Cu" signal "GND3")
		(18 "In8.Cu" signal "VCC")
		(20 "In9.Cu" signal "VCC1")
		(22 "In10.Cu" signal "GND4")
		(24 "In11.Cu" signal "IN4")
		(26 "In12.Cu" signal "GND5")
		(28 "In13.Cu" signal "IN5")
		(30 "In14.Cu" signal "GND6")
		(32 "In15.Cu" signal "IN6")
		(34 "In16.Cu" signal "GND7")
		(2 "B.Cu" signal "BOTTOM")
		(9 "F.Adhes" user "F.Adhesive")
		(11 "B.Adhes" user "B.Adhesive")
		(13 "F.Paste" user "Package Geometry/Pastemask Top")
		(15 "B.Paste" user "Package Geometry/Pastemask Bottom")
		(5 "F.SilkS" user "Ref Des/Silkscreen Top")
		(7 "B.SilkS" user "Ref Des/Silkscreen Bottom")
		(1 "F.Mask" user "Board Geometry/Soldermask Top")
		(3 "B.Mask" user "Board Geometry/Soldermask Bottom")
		(17 "Dwgs.User" user "User.Drawings")
		(19 "Cmts.User" user "User.Comments")
		(21 "Eco1.User" user "User.Eco1")
		(23 "Eco2.User" user "User.Eco2")
		(25 "Edge.Cuts" user "Board Geometry/Outline")
		(27 "Margin" user)
		(31 "F.CrtYd" user "Package Geometry/Place Bound Top")
		(29 "B.CrtYd" user "Package Geometry/Place Bound Bottom")
		(35 "F.Fab" user "Ref Des/Assembly Top")
		(33 "B.Fab" user "Ref Des/Assembly Bottom")
	)
	(footprint ""
		(layer "B.Cu")
		(at 13.018262 -389.526526 -90)
		(property "Reference" "PR6621"
			(at 0 0 90)
			(layer "B.SilkS")
			(hide yes)
			(effects
				(font
					(size 1.27 1.27)
				)
				(justify mirror)
			)
		)
		(property "Value" ""
			(at 0 0 90)
			(layer "B.Fab")
			(effects
				(font
					(size 1.27 1.27)
				)
				(justify mirror)
			)
		)
		(duplicate_pad_numbers_are_jumpers no)
		(fp_line
			(start -0.7874 0.4064)
			(end 0.7874 0.4064)
			(stroke
				(width 0.1524)
				(type default)
			)
			(layer "B.SilkS")
		)
		(fp_line
			(start 0.7874 0.4064)
			(end 0.7874 -0.4064)
			(stroke
				(width 0.1524)
				(type default)
			)
			(layer "B.SilkS")
		)
		(fp_line
			(start -0.7874 -0.4064)
			(end -0.7874 0.4064)
			(stroke
				(width 0.1524)
				(type default)
			)
			(layer "B.SilkS")
		)
		(fp_line
			(start 0.7874 -0.4064)
			(end -0.7874 -0.4064)
			(stroke
				(width 0.1524)
				(type default)
			)
			(layer "B.SilkS")
		)
		(fp_line
			(start -0.67945 0.3048)
			(end -0.120396 0.3048)
			(stroke
				(width 0.1)
				(type default)
			)
			(layer "B.Fab")
		)
		(fp_line
			(start -0.120396 0.3048)
			(end -0.120396 0.2794)
			(stroke
				(width 0.1)
				(type default)
			)
			(layer "B.Fab")
		)
		(fp_line
			(start 0.12065 0.3048)
			(end 0.67945 0.3048)
			(stroke
				(width 0.1)
				(type default)
			)
			(layer "B.Fab")
		)
		(fp_line
			(start 0.67945 0.3048)
			(end 0.67945 -0.305054)
			(stroke
				(width 0.1)
				(type default)
			)
			(layer "B.Fab")
		)
		(fp_line
			(start -0.120396 0.2794)
			(end 0.12065 0.2794)
			(stroke
				(width 0.1)
				(type default)
			)
			(layer "B.Fab")
		)
		(fp_line
			(start 0.12065 0.2794)
			(end 0.12065 0.3048)
			(stroke
				(width 0.1)
				(type default)
			)
			(layer "B.Fab")
		)
		(fp_line
			(start -0.12065 -0.2794)
			(end -0.12065 -0.3048)
			(stroke
				(width 0.1)
				(type default)
			)
			(layer "B.Fab")
		)
		(fp_line
			(start 0.12065 -0.2794)
			(end -0.12065 -0.2794)
			(stroke
				(width 0.1)
				(type default)
			)
			(layer "B.Fab")
		)
		(fp_line
			(start -0.67945 -0.3048)
			(end -0.67945 0.3048)
			(stroke
				(width 0.1)
				(type default)
			)
			(layer "B.Fab")
		)
		(fp_line
			(start -0.12065 -0.3048)
			(end -0.67945 -0.3048)
			(stroke
				(width 0.1)
				(type default)
			)
			(layer "B.Fab")
		)
		(fp_line
			(start 0.12065 -0.305054)
			(end 0.12065 -0.2794)
			(stroke
				(width 0.1)
				(type default)
			)
			(layer "B.Fab")
		)
		(fp_line
			(start 0.67945 -0.305054)
			(end 0.12065 -0.305054)
			(stroke
				(width 0.1)
				(type default)
			)
			(layer "B.Fab")
		)
		(pad "1" smd circle
			(at 0.40005 0 90)
			(size 0 0)
			(layers "B.Cu" "B.Mask" "B.Paste")
			(net "P0V9_RETIMER_CPU1_PVCC")
		)
		(pad "2" smd circle
			(at -0.40005 0 90)
			(size 0 0)
			(layers "B.Cu" "B.Mask" "B.Paste")
			(net "P0V9_RETIMER_CPU1_VCC1")
		)
	)
	(footprint ""
		(layer "B.Cu")
		(at 136.93648 -9.032748 -90)
		(property "Reference" "R3777"
			(at 0 0 90)
			(layer "B.SilkS")
			(hide yes)
			(effects
				(font
					(size 1.27 1.27)
				)
				(justify mirror)
			)
		)
		(property "Value" ""
			(at 0 0 90)
			(layer "B.Fab")
			(effects
				(font
					(size 1.27 1.27)
				)
				(justify mirror)
			)
		)
		(duplicate_pad_numbers_are_jumpers no)
		(fp_line
			(start -0.7874 0.4064)
			(end 0.7874 0.4064)
			(stroke
				(width 0.1524)
				(type default)
			)
			(layer "B.SilkS")
		)
		(fp_line
			(start 0.7874 0.4064)
			(end 0.7874 -0.4064)
			(stroke
				(width 0.1524)
				(type default)
			)
			(layer "B.SilkS")
		)
		(fp_line
			(start -0.7874 -0.4064)
			(end -0.7874 0.4064)
			(stroke
				(width 0.1524)
				(type default)
			)
			(layer "B.SilkS")
		)
		(fp_line
			(start 0.7874 -0.4064)
			(end -0.7874 -0.4064)
			(stroke
				(width 0.1524)
				(type default)
			)
			(layer "B.SilkS")
		)
		(fp_line
			(start -0.67945 0.3048)
			(end -0.120396 0.3048)
			(stroke
				(width 0.1)
				(type default)
			)
			(layer "B.Fab")
		)
		(fp_line
			(start -0.120396 0.3048)
			(end -0.120396 0.2794)
			(stroke
				(width 0.1)
				(type default)
			)
			(layer "B.Fab")
		)
		(fp_line
			(start 0.12065 0.3048)
			(end 0.67945 0.3048)
			(stroke
				(width 0.1)
				(type default)
			)
			(layer "B.Fab")
		)
		(fp_line
			(start 0.67945 0.3048)
			(end 0.67945 -0.305054)
			(stroke
				(width 0.1)
				(type default)
			)
			(layer "B.Fab")
		)
		(fp_line
			(start -0.120396 0.2794)
			(end 0.12065 0.2794)
			(stroke
				(width 0.1)
				(type default)
			)
			(layer "B.Fab")
		)
		(fp_line
			(start 0.12065 0.2794)
			(end 0.12065 0.3048)
			(stroke
				(width 0.1)
				(type default)
			)
			(layer "B.Fab")
		)
		(fp_line
			(start -0.12065 -0.2794)
			(end -0.12065 -0.3048)
			(stroke
				(width 0.1)
				(type default)
			)
			(layer "B.Fab")
		)
		(fp_line
			(start 0.12065 -0.2794)
			(end -0.12065 -0.2794)
			(stroke
				(width 0.1)
				(type default)
			)
			(layer "B.Fab")
		)
		(fp_line
			(start -0.67945 -0.3048)
			(end -0.67945 0.3048)
			(stroke
				(width 0.1)
				(type default)
			)
			(layer "B.Fab")
		)
		(fp_line
			(start -0.12065 -0.3048)
			(end -0.67945 -0.3048)
			(stroke
				(width 0.1)
				(type default)
			)
			(layer "B.Fab")
		)
		(fp_line
			(start 0.12065 -0.305054)
			(end 0.12065 -0.2794)
			(stroke
				(width 0.1)
				(type default)
			)
			(layer "B.Fab")
		)
		(fp_line
			(start 0.67945 -0.305054)
			(end 0.12065 -0.305054)
			(stroke
				(width 0.1)
				(type default)
			)
			(layer "B.Fab")
		)
		(pad "1" smd circle
			(at 0.40005 0 90)
			(size 0 0)
			(layers "B.Cu" "B.Mask" "B.Paste")
			(net "FM_UARTSW_LSB_N")
		)
		(pad "2" smd circle
			(at -0.40005 0 90)
			(size 0 0)
			(layers "B.Cu" "B.Mask" "B.Paste")
			(net "FM_UARTSW_LSB_R")
		)
	)
)
